# BASEBOARD_FAB2 (Tioga Pass) — schematic netlist excerpt (pin names and nets, part order shuffled) for the footprints in the layout excerpt that follows; sources: Cadence DE-HDL packaged netlist, KiCad conversion of Wiwynn_Tioga_Pass_MB.brd

C25W90  CAP_A  0.1UF 16V 10% X7R  pkg 0402V  page 252 : A = P5V_VGA_D ; B = GND
C1W18  CAP_A  0.1UF 16V 10% X7R  pkg 0402V  page 176 : A = P3V3_STBY ; B = GND
C1M34  CAP_A  0.01UF 25V 10% X7R  pkg 0402V  page 113 : A = P3V3_STBY ; B = GND

(kicad_pcb
	(version 20260206)
	(generator "pcbnew")
	(generator_version "10.0")
	(general
		(thickness 1.6)
		(legacy_teardrops no)
	)
	(paper "A4")
	(title_block
		(title "Wiwynn_Tioga_Pass_MB.brd")
		(comment 1 "Tioga Pass / footprints 2531-2533 of 4770")
	)
	(layers
		(0 "F.Cu" signal "TOP")
		(4 "In1.Cu" signal "L2GND")
		(6 "In2.Cu" signal "L3")
		(8 "In3.Cu" signal "L4GND")
		(10 "In4.Cu" signal "L5")
		(12 "In5.Cu" signal "L6GND")
		(14 "In6.Cu" signal "L7VCC")
		(16 "In7.Cu" signal "L8VCC")
		(18 "In8.Cu" signal "L9GND")
		(20 "In9.Cu" signal "L10")
		(22 "In10.Cu" signal "L11GND")
		(24 "In11.Cu" signal "L12")
		(26 "In12.Cu" signal "L13GND")
		(2 "B.Cu" signal "BOTTOM")
		(9 "F.Adhes" user "F.Adhesive")
		(11 "B.Adhes" user "B.Adhesive")
		(13 "F.Paste" user "Package Geometry/Pastemask Top")
		(15 "B.Paste" user "Package Geometry/Pastemask Bottom")
		(5 "F.SilkS" user "Ref Des/Silkscreen Top")
		(7 "B.SilkS" user "Ref Des/Silkscreen Bottom")
		(1 "F.Mask" user "Board Geometry/Soldermask Top")
		(3 "B.Mask" user "Board Geometry/Soldermask Bottom")
		(17 "Dwgs.User" user "User.Drawings")
		(19 "Cmts.User" user "User.Comments")
		(21 "Eco1.User" user "User.Eco1")
		(23 "Eco2.User" user "User.Eco2")
		(25 "Edge.Cuts" user "Board Geometry/Outline")
		(27 "Margin" user)
		(31 "F.CrtYd" user "Package Geometry/Place Bound Top")
		(29 "B.CrtYd" user "Package Geometry/Place Bound Bottom")
		(35 "F.Fab" user "Ref Des/Assembly Top")
		(33 "B.Fab" user "Ref Des/Assembly Bottom")
	)
	(footprint ""
		(layer "B.Cu")
		(at 473.122498 -135.78459 -90)
		(property "Reference" "C1W18"
			(at 0.8382 -0.67818 270)
			(unlocked yes)
			(layer "B.SilkS")
			(effects
				(font
					(size 0.4064 0.254)
					(thickness 0.1524)
				)
				(justify left mirror)
			)
		)
		(property "Value" ""
			(at 0 0 90)
			(layer "B.Fab")
			(effects
				(font
					(size 1.27 1.27)
				)
				(justify mirror)
			)
		)
		(duplicate_pad_numbers_are_jumpers no)
		(fp_poly
			(pts
				(xy -0.3048 -0.1016) (xy -0.3048 0.9906) (xy 0.3048 0.9906) (xy 0.3048 -0.1016)
			)
			(stroke
				(width 0)
				(type default)
			)
			(fill no)
			(layer "B.CrtYd")
		)
		(fp_line
			(start -0.3048 0.9906)
			(end -0.3048 -0.1016)
			(stroke
				(width 0.1)
				(type default)
			)
			(layer "B.Fab")
		)
		(fp_line
			(start 0.3048 0.9906)
			(end -0.3048 0.9906)
			(stroke
				(width 0.1)
				(type default)
			)
			(layer "B.Fab")
		)
		(fp_line
			(start -0.3048 -0.1016)
			(end 0.3048 -0.1016)
			(stroke
				(width 0.1)
				(type default)
			)
			(layer "B.Fab")
		)
		(fp_line
			(start 0.3048 -0.1016)
			(end 0.3048 0.9906)
			(stroke
				(width 0.1)
				(type default)
			)
			(layer "B.Fab")
		)
		(pad "1" smd rect
			(at 0 0 90)
			(size 0.508 0.508)
			(layers "B.Cu" "B.Mask" "B.Paste")
			(net "P3V3_STBY")
		)
		(pad "2" smd rect
			(at 0 0.889 90)
			(size 0.508 0.508)
			(layers "B.Cu" "B.Mask" "B.Paste")
			(net "GND")
		)
		(zone
			(layer "B.Cu")
			(hatch none 0.5)
			(connect_pads
				(clearance 0)
			)
			(min_thickness 0.25)
			(keepout
				(tracks not_allowed)
				(vias allowed)
				(pads allowed)
				(copperpour not_allowed)
				(footprints allowed)
			)
			(placement
				(enabled no)
				(sheetname "")
			)
			(fill
				(thermal_gap 0.5)
				(thermal_bridge_width 0.5)
				(island_removal_mode 0)
			)
			(polygon
				(pts
					(xy 472.487498 -135.53059) (xy 472.487498 -136.03859) (xy 472.868498 -136.03859) (xy 472.868498 -135.53059)
				)
			)
		)
		(zone
			(layer "B.Cu")
			(hatch none 0.5)
			(connect_pads
				(clearance 0)
			)
			(min_thickness 0.25)
			(keepout
				(tracks allowed)
				(vias not_allowed)
				(pads allowed)
				(copperpour not_allowed)
				(footprints allowed)
			)
			(placement
				(enabled no)
				(sheetname "")
			)
			(fill
				(thermal_gap 0.5)
				(thermal_bridge_width 0.5)
				(island_removal_mode 0)
			)
			(polygon
				(pts
					(xy 472.868498 -135.53059) (xy 472.868498 -136.03859) (xy 472.487498 -136.03859) (xy 472.487498 -135.53059)
				)
			)
		)
	)
	(footprint ""
		(layer "B.Cu")
		(at 500.246142 -43.04284 -90)
		(property "Reference" "C25W90"
			(at 0.8382 -0.67818 270)
			(unlocked yes)
			(layer "B.SilkS")
			(effects
				(font
					(size 0.4064 0.254)
					(thickness 0.1524)
				)
				(justify left mirror)
			)
		)
		(property "Value" ""
			(at 0 0 90)
			(layer "B.Fab")
			(effects
				(font
					(size 1.27 1.27)
				)
				(justify mirror)
			)
		)
		(duplicate_pad_numbers_are_jumpers no)
		(fp_poly
			(pts
				(xy -0.3048 -0.1016) (xy -0.3048 0.9906) (xy 0.3048 0.9906) (xy 0.3048 -0.1016)
			)
			(stroke
				(width 0)
				(type default)
			)
			(fill no)
			(layer "B.CrtYd")
		)
		(fp_line
			(start -0.3048 0.9906)
			(end -0.3048 -0.1016)
			(stroke
				(width 0.1)
				(type default)
			)
			(layer "B.Fab")
		)
		(fp_line
			(start 0.3048 0.9906)
			(end -0.3048 0.9906)
			(stroke
				(width 0.1)
				(type default)
			)
			(layer "B.Fab")
		)
		(fp_line
			(start -0.3048 -0.1016)
			(end 0.3048 -0.1016)
			(stroke
				(width 0.1)
				(type default)
			)
			(layer "B.Fab")
		)
		(fp_line
			(start 0.3048 -0.1016)
			(end 0.3048 0.9906)
			(stroke
				(width 0.1)
				(type default)
			)
			(layer "B.Fab")
		)
		(pad "1" smd rect
			(at 0 0 90)
			(size 0.508 0.508)
			(layers "B.Cu" "B.Mask" "B.Paste")
			(net "P5V_VGA_D")
		)
		(pad "2" smd rect
			(at 0 0.889 90)
			(size 0.508 0.508)
			(layers "B.Cu" "B.Mask" "B.Paste")
			(net "GND")
		)
		(zone
			(layer "B.Cu")
			(hatch none 0.5)
			(connect_pads
				(clearance 0)
			)
			(min_thickness 0.25)
			(keepout
				(tracks not_allowed)
				(vias allowed)
				(pads allowed)
				(copperpour not_allowed)
				(footprints allowed)
			)
			(placement
				(enabled no)
				(sheetname "")
			)
			(fill
				(thermal_gap 0.5)
				(thermal_bridge_width 0.5)
				(island_removal_mode 0)
			)
			(polygon
				(pts
					(xy 499.611142 -42.78884) (xy 499.611142 -43.29684) (xy 499.992142 -43.29684) (xy 499.992142 -42.78884)
				)
			)
		)
		(zone
			(layer "B.Cu")
			(hatch none 0.5)
			(connect_pads
				(clearance 0)
			)
			(min_thickness 0.25)
			(keepout
				(tracks allowed)
				(vias not_allowed)
				(pads allowed)
				(copperpour not_allowed)
				(footprints allowed)
			)
			(placement
				(enabled no)
				(sheetname "")
			)
			(fill
				(thermal_gap 0.5)
				(thermal_bridge_width 0.5)
				(island_removal_mode 0)
			)
			(polygon
				(pts
					(xy 499.992142 -42.78884) (xy 499.992142 -43.29684) (xy 499.611142 -43.29684) (xy 499.611142 -42.78884)
				)
			)
		)
	)
	(footprint ""
		(layer "B.Cu")
		(at 449.1736 -129.3622 180)
		(property "Reference" "C1M34"
			(at 0 0 0)
			(layer "B.SilkS")
			(hide yes)
			(effects
				(font
					(size 1.27 1.27)
				)
				(justify mirror)
			)
		)
		(property "Value" ""
			(at 0 0 0)
			(layer "B.Fab")
			(effects
				(font
					(size 1.27 1.27)
				)
				(justify mirror)
			)
		)
		(duplicate_pad_numbers_are_jumpers no)
		(fp_poly
			(pts
				(xy -0.3048 -0.1016) (xy -0.3048 0.9906) (xy 0.3048 0.9906) (xy 0.3048 -0.1016)
			)
			(stroke
				(width 0)
				(type default)
			)
			(fill no)
			(layer "B.CrtYd")
		)
		(fp_line
			(start 0.3048 0.9906)
			(end -0.3048 0.9906)
			(stroke
				(width 0.1)
				(type default)
			)
			(layer "B.Fab")
		)
		(fp_line
			(start 0.3048 -0.1016)
			(end 0.3048 0.9906)
			(stroke
				(width 0.1)
				(type default)
			)
			(layer "B.Fab")
		)
		(fp_line
			(start -0.3048 0.9906)
			(end -0.3048 -0.1016)
			(stroke
				(width 0.1)
				(type default)
			)
			(layer "B.Fab")
		)
		(fp_line
			(start -0.3048 -0.1016)
			(end 0.3048 -0.1016)
			(stroke
				(width 0.1)
				(type default)
			)
			(layer "B.Fab")
		)
		(pad "1" smd rect
			(at 0 0)
			(size 0.508 0.508)
			(layers "B.Cu" "B.Mask" "B.Paste")
			(net "P3V3_STBY")
		)
		(pad "2" smd rect
			(at 0 0.889)
			(size 0.508 0.508)
			(layers "B.Cu" "B.Mask" "B.Paste")
			(net "GND")
		)
		(zone
			(layer "B.Cu")
			(hatch none 0.5)
			(connect_pads
				(clearance 0)
			)
			(min_thickness 0.25)
			(keepout
				(tracks not_allowed)
				(vias allowed)
				(pads allowed)
				(copperpour not_allowed)
				(footprints allowed)
			)
			(placement
				(enabled no)
				(sheetname "")
			)
			(fill
				(thermal_gap 0.5)
				(thermal_bridge_width 0.5)
				(island_removal_mode 0)
			)
			(polygon
				(pts
					(xy 448.9196 -129.9972) (xy 449.4276 -129.9972) (xy 449.4276 -129.6162) (xy 448.9196 -129.6162)
				)
			)
		)
		(zone
			(layer "B.Cu")
			(hatch none 0.5)
			(connect_pads
				(clearance 0)
			)
			(min_thickness 0.25)
			(keepout
				(tracks allowed)
				(vias not_allowed)
				(pads allowed)
				(copperpour not_allowed)
				(footprints allowed)
			)
			(placement
				(enabled no)
				(sheetname "")
			)
			(fill
				(thermal_gap 0.5)
				(thermal_bridge_width 0.5)
				(island_removal_mode 0)
			)
			(polygon
				(pts
					(xy 448.9196 -129.6162) (xy 449.4276 -129.6162) (xy 449.4276 -129.9972) (xy 448.9196 -129.9972)
				)
			)
		)
	)
)
